(kicad_pcb
	(version 20241229)
	(generator "pcbnew")
	(generator_version "9.0")
	(general
		(thickness 1.6)
		(legacy_teardrops no)
	)
	(paper "A4")
	(title_block
		(title "GMSL Deserializer")
		(date "2025-10-09")
		(rev "1.0.4")
		(company "Antmicro Ltd")
		(comment 1 "www.antmicro.com")
		(comment 9 "footprints 13-13 of 235")
	)
	(layers
		(0 "F.Cu" signal)
		(4 "In1.Cu" power)
		(6 "In2.Cu" power)
		(2 "B.Cu" signal)
		(9 "F.Adhes" user "F.Adhesive")
		(11 "B.Adhes" user "B.Adhesive")
		(13 "F.Paste" user)
		(15 "B.Paste" user)
		(5 "F.SilkS" user "F.Silkscreen")
		(7 "B.SilkS" user "B.Silkscreen")
		(1 "F.Mask" user)
		(3 "B.Mask" user)
		(17 "Dwgs.User" user "User.Drawings")
		(19 "Cmts.User" user "User.Comments")
		(21 "Eco1.User" user "User.Eco1")
		(23 "Eco2.User" user "User.Eco2")
		(25 "Edge.Cuts" user)
		(27 "Margin" user)
		(31 "F.CrtYd" user "F.Courtyard")
		(29 "B.CrtYd" user "B.Courtyard")
		(35 "F.Fab" user)
		(33 "B.Fab" user)
	)
	(footprint "antmicro-footprints:L_Coilcraft-1210POC"
		(layer "F.Cu")
		(at 159.766 56.642 90)
		(property "Reference" "L8"
			(at -0.635 -1.7 90)
			(layer "F.SilkS")
			(effects
				(font
					(size 0.7 0.7)
					(thickness 0.15)
				)
				(justify left bottom)
			)
		)
		(property "Value" "L_6u8_1A_Coilcraft-1210POC"
			(at 0 2.4 90)
			(layer "F.Fab")
			(effects
				(font
					(size 0.7 0.7)
					(thickness 0.15)
				)
				(justify left bottom)
			)
		)
		(property "Datasheet" "https://www.coilcraft.com/getmedia/5e8de018-68c5-4442-84ce-d5212c44660c/1210poc.pdf"
			(at 0 0 90)
			(layer "F.Fab")
			(hide yes)
			(effects
				(font
					(size 1.27 1.27)
					(thickness 0.15)
				)
			)
		)
		(property "Description" "Power Inductor (SMT), 6.8 µH, 9.2 A, Shielded, 12.8 A, XAL7070"
			(at 0 0 90)
			(layer "F.Fab")
			(hide yes)
			(effects
				(font
					(size 1.27 1.27)
					(thickness 0.15)
				)
			)
		)
		(property "Author" "Antmicro"
			(at 216.408 -103.124 0)
			(layer "F.Fab")
			(hide yes)
			(effects
				(font
					(size 1 1)
					(thickness 0.15)
				)
			)
		)
		(property "IMax" "1.36 A"
			(at 216.408 -103.124 0)
			(layer "F.Fab")
			(hide yes)
			(effects
				(font
					(size 1 1)
					(thickness 0.15)
				)
			)
		)
		(property "ISat" "1 A"
			(at 216.408 -103.124 0)
			(layer "F.Fab")
			(hide yes)
			(effects
				(font
					(size 1 1)
					(thickness 0.15)
				)
			)
		)
		(property "License" "Apache-2.0"
			(at 216.408 -103.124 0)
			(layer "F.Fab")
			(hide yes)
			(effects
				(font
					(size 1 1)
					(thickness 0.15)
				)
			)
		)
		(property "MPN" "1210POC-682"
			(at 216.408 -103.124 0)
			(layer "F.Fab")
			(hide yes)
			(effects
				(font
					(size 1 1)
					(thickness 0.15)
				)
			)
		)
		(property "Manufacturer" "Coilcraft"
			(at 216.408 -103.124 0)
			(layer "F.Fab")
			(hide yes)
			(effects
				(font
					(size 1 1)
					(thickness 0.15)
				)
			)
		)
		(property "Size" "2.67x3.3"
			(at 216.408 -103.124 0)
			(layer "F.Fab")
			(hide yes)
			(effects
				(font
					(size 1 1)
					(thickness 0.15)
				)
			)
		)
		(property "Val" "6u8/1A"
			(at 216.408 -103.124 0)
			(layer "F.Fab")
			(hide yes)
			(effects
				(font
					(size 1 1)
					(thickness 0.15)
				)
			)
		)
		(sheetname "/Power/")
		(sheetfile "power.kicad_sch")
		(attr smd)
		(fp_line
			(start -0.7 -1.4)
			(end 0.7 -1.4)
			(stroke
				(width 0.15)
				(type solid)
			)
			(layer "F.SilkS")
		)
		(fp_line
			(start -0.7 1.4)
			(end 0.7 1.4)
			(stroke
				(width 0.15)
				(type solid)
			)
			(layer "F.SilkS")
		)
		(fp_rect
			(start -1.9 -1.585)
			(end 1.9 1.585)
			(stroke
				(width 0.05)
				(type solid)
			)
			(fill no)
			(layer "F.CrtYd")
		)
		(fp_line
			(start 1.65 -1.335)
			(end -1.65 -1.335)
			(stroke
				(width 0.15)
				(type solid)
			)
			(layer "F.Fab")
		)
		(fp_line
			(start 1.65 1.335)
			(end 1.65 -1.335)
			(stroke
				(width 0.15)
				(type solid)
			)
			(layer "F.Fab")
		)
		(fp_line
			(start 1.65 1.335)
			(end -1.65 1.335)
			(stroke
				(width 0.15)
				(type solid)
			)
			(layer "F.Fab")
		)
		(fp_line
			(start -1.65 1.335)
			(end -1.65 -1.335)
			(stroke
				(width 0.15)
				(type solid)
			)
			(layer "F.Fab")
		)
		(pad "1" smd rect
			(at -1.27 0 90)
			(size 0.65 2.65)
			(layers "F.Cu" "F.Mask" "F.Paste")
			(net 54 "Net-(L4-Pad2)")
			(pintype "passive")
		)
		(pad "2" smd rect
			(at 1.27 0 90)
			(size 0.65 2.65)
			(layers "F.Cu" "F.Mask" "F.Paste")
			(net 58 "Net-(L12-Pad1)")
			(pintype "passive")
		)
	)
)
